(kicad_pcb
	(version 20241229)
	(generator "pcbnew")
	(generator_version "9.0")
	(general
		(thickness 1.711)
		(legacy_teardrops no)
	)
	(paper "A4")
	(title_block
		(title "Antmicro Baseboard for Jetson AGX Thor")
		(date "2026-02-18")
		(rev "1.1.0")
		(company "Antmicro Ltd")
		(comment 1 "www.antmicro.com")
		(comment 9 "footprints 1137-1140 of 1170")
	)
	(layers
		(0 "F.Cu" signal)
		(4 "In1.Cu" signal)
		(6 "In2.Cu" signal)
		(8 "In3.Cu" signal)
		(10 "In4.Cu" jumper)
		(12 "In5.Cu" signal)
		(14 "In6.Cu" signal)
		(16 "In7.Cu" signal)
		(18 "In8.Cu" signal)
		(2 "B.Cu" signal)
		(9 "F.Adhes" user "F.Adhesive")
		(11 "B.Adhes" user "B.Adhesive")
		(13 "F.Paste" user)
		(15 "B.Paste" user)
		(5 "F.SilkS" user "F.Silkscreen")
		(7 "B.SilkS" user "B.Silkscreen")
		(1 "F.Mask" user)
		(3 "B.Mask" user)
		(17 "Dwgs.User" user "User.Drawings")
		(19 "Cmts.User" user "User.Comments")
		(21 "Eco1.User" user "User.Eco1")
		(23 "Eco2.User" user "User.Eco2")
		(25 "Edge.Cuts" user)
		(27 "Margin" user)
		(31 "F.CrtYd" user "F.Courtyard")
		(29 "B.CrtYd" user "B.Courtyard")
		(35 "F.Fab" user)
		(33 "B.Fab" user)
	)
	(footprint "antmicro-footprints:Oscillator_SMD_ECS_2520MV_2.5x2mm"
		(layer "B.Cu")
		(at 128.8 132 90)
		(descr "Miniature Crystal Clock Oscillator ECS 2520MV series")
		(tags "Crystal Clock Oscillator ECS 2520MV SMD")
		(property "Reference" "Y3"
			(at 2.2 0.2 0)
			(layer "B.SilkS")
			(effects
				(font
					(size 0.7 0.7)
					(thickness 0.15)
				)
				(justify right top mirror)
			)
		)
		(property "Value" "Oscillator_32.768kHz_ECS_2520MV"
			(at 0 -2.499 90)
			(layer "B.Fab")
			(effects
				(font
					(size 0.7 0.7)
					(thickness 0.15)
				)
				(justify right top mirror)
			)
		)
		(property "Datasheet" "https://ecsxtal.com/store/pdf/ECS-327MVATX.pdf"
			(at 0 0 90)
			(layer "B.Fab")
			(hide yes)
			(effects
				(font
					(size 1.27 1.27)
					(thickness 0.15)
				)
				(justify mirror)
			)
		)
		(property "Description" "32.768 kHz XO (Standard) CMOS Oscillator 1.6V ~ 3.6V Enable/Disable 4-SMD, No Lead"
			(at 0 0 90)
			(layer "B.Fab")
			(hide yes)
			(effects
				(font
					(size 1.27 1.27)
					(thickness 0.15)
				)
				(justify mirror)
			)
		)
		(property "Manufacturer" "ECS Inc. International"
			(at 0 0 270)
			(unlocked yes)
			(layer "B.Fab")
			(hide yes)
			(effects
				(font
					(size 1 1)
					(thickness 0.15)
				)
				(justify mirror)
			)
		)
		(property "MPN" "ECS-327MVATX-2-CN-TR3"
			(at 0 0 270)
			(unlocked yes)
			(layer "B.Fab")
			(hide yes)
			(effects
				(font
					(size 1 1)
					(thickness 0.15)
				)
				(justify mirror)
			)
		)
		(property "Val" "32.768 kHz"
			(at 0 0 270)
			(unlocked yes)
			(layer "B.Fab")
			(hide yes)
			(effects
				(font
					(size 1 1)
					(thickness 0.15)
				)
				(justify mirror)
			)
		)
		(property "Author" "Antmicro"
			(at 0 0 270)
			(unlocked yes)
			(layer "B.Fab")
			(hide yes)
			(effects
				(font
					(size 1 1)
					(thickness 0.15)
				)
				(justify mirror)
			)
		)
		(property "License" "Apache-2.0"
			(at 0 0 270)
			(unlocked yes)
			(layer "B.Fab")
			(hide yes)
			(effects
				(font
					(size 1 1)
					(thickness 0.15)
				)
				(justify mirror)
			)
		)
		(sheetname "/M.2/")
		(sheetfile "m2.kicad_sch")
		(attr smd)
		(fp_line
			(start -0.172 -1.36)
			(end 0.17 -1.36)
			(stroke
				(width 0.15)
				(type solid)
			)
			(layer "B.SilkS")
		)
		(fp_line
			(start 1.11 -0.32)
			(end 1.11 0.32)
			(stroke
				(width 0.15)
				(type solid)
			)
			(layer "B.SilkS")
		)
		(fp_line
			(start -1.111 -0.32)
			(end -1.111 0.32)
			(stroke
				(width 0.15)
				(type solid)
			)
			(layer "B.SilkS")
		)
		(fp_line
			(start -0.16 1.361)
			(end 0.17 1.361)
			(stroke
				(width 0.15)
				(type solid)
			)
			(layer "B.SilkS")
		)
		(fp_circle
			(center -1.1 1.5)
			(end -1.049 1.5)
			(stroke
				(width 0.15)
				(type solid)
			)
			(fill yes)
			(layer "B.SilkS")
		)
		(fp_rect
			(start -1.25 1.5)
			(end 1.25 -1.5)
			(stroke
				(width 0.05)
				(type solid)
			)
			(fill no)
			(layer "B.CrtYd")
		)
		(fp_line
			(start -1 0.75)
			(end -0.5 1.25)
			(stroke
				(width 0.15)
				(type solid)
			)
			(layer "B.Fab")
		)
		(fp_rect
			(start 1 -1.249)
			(end -1 1.25)
			(stroke
				(width 0.15)
				(type solid)
			)
			(fill no)
			(layer "B.Fab")
		)
		(fp_text user "Author: Antmicro"
			(at -1.25 -5.102 90)
			(layer "B.Fab")
			(effects
				(font
					(size 0.7 0.7)
					(thickness 0.15)
				)
				(justify right top mirror)
			)
		)
		(fp_text user "${REFERENCE}"
			(at -1.25 -3.9 90)
			(layer "B.Fab")
			(effects
				(font
					(size 0.7 0.7)
					(thickness 0.15)
				)
				(justify right top mirror)
			)
		)
		(fp_text user "License: Apache-2.0"
			(at -1.25 -6.302 90)
			(layer "B.Fab")
			(effects
				(font
					(size 0.7 0.7)
					(thickness 0.15)
				)
				(justify right top mirror)
			)
		)
		(pad "1" smd roundrect
			(at -0.725 0.927 90)
			(size 0.8 0.9)
			(layers "B.Cu" "B.Mask" "B.Paste")
			(roundrect_rratio 0.25)
			(net 2 "+3V3")
			(pinfunction "EN")
			(pintype "input")
		)
		(pad "2" smd roundrect
			(at -0.725 -0.925 90)
			(size 0.8 0.9)
			(layers "B.Cu" "B.Mask" "B.Paste")
			(roundrect_rratio 0.25)
			(net 1 "GND")
			(pinfunction "GND")
			(pintype "power_in")
		)
		(pad "3" smd roundrect
			(at 0.723 -0.925 90)
			(size 0.8 0.9)
			(layers "B.Cu" "B.Mask" "B.Paste")
			(roundrect_rratio 0.25)
			(net 1005 "/M.2/SUSCLK")
			(pinfunction "OUT")
			(pintype "output")
		)
		(pad "4" smd roundrect
			(at 0.723 0.927 90)
			(size 0.8 0.9)
			(layers "B.Cu" "B.Mask" "B.Paste")
			(roundrect_rratio 0.25)
			(net 2 "+3V3")
			(pinfunction "VDD")
			(pintype "power_in")
		)
	)
	(footprint "antmicro-footprints:TP_SMD_0.75mm"
		(layer "B.Cu")
		(at 126.8 69.4 90)
		(property "Reference" "TP31"
			(at 0.5 -0.3 90)
			(layer "B.SilkS")
			(effects
				(font
					(size 0.7 0.7)
					(thickness 0.15)
				)
				(justify right top mirror)
			)
		)
		(property "Value" "TP_0.75mm_SMD"
			(at 0 -1.2 90)
			(layer "B.Fab")
			(effects
				(font
					(size 0.7 0.7)
					(thickness 0.15)
				)
				(justify right top mirror)
			)
		)
		(property "Description" "SMT test point"
			(at 0 0 90)
			(layer "B.Fab")
			(hide yes)
			(effects
				(font
					(size 1.27 1.27)
					(thickness 0.15)
				)
				(justify mirror)
			)
		)
		(property "MPN" ""
			(at 0 0 270)
			(unlocked yes)
			(layer "B.Fab")
			(hide yes)
			(effects
				(font
					(size 1 1)
					(thickness 0.15)
				)
				(justify mirror)
			)
		)
		(property "Manufacturer" ""
			(at 0 0 270)
			(unlocked yes)
			(layer "B.Fab")
			(hide yes)
			(effects
				(font
					(size 1 1)
					(thickness 0.15)
				)
				(justify mirror)
			)
		)
		(property "Author" "Antmicro"
			(at 0 0 270)
			(unlocked yes)
			(layer "B.Fab")
			(hide yes)
			(effects
				(font
					(size 1 1)
					(thickness 0.15)
				)
				(justify mirror)
			)
		)
		(property "License" "Apache-2.0"
			(at 0 0 270)
			(unlocked yes)
			(layer "B.Fab")
			(hide yes)
			(effects
				(font
					(size 1 1)
					(thickness 0.15)
				)
				(justify mirror)
			)
		)
		(sheetname "/SoM_Power/")
		(sheetfile "som_power.kicad_sch")
		(attr exclude_from_pos_files exclude_from_bom)
		(fp_circle
			(center 0 0)
			(end 0.475 0)
			(stroke
				(width 0.05)
				(type default)
			)
			(fill no)
			(layer "B.CrtYd")
		)
		(fp_text user "License: Apache-2.0"
			(at -0.4 -5.101 90)
			(layer "B.Fab")
			(effects
				(font
					(size 0.7 0.7)
					(thickness 0.15)
				)
				(justify right top mirror)
			)
		)
		(fp_text user "${REFERENCE}"
			(at -0.4 -2.7 90)
			(layer "B.Fab")
			(effects
				(font
					(size 0.7 0.7)
					(thickness 0.15)
				)
				(justify right top mirror)
			)
		)
		(fp_text user "Author: Antmicro"
			(at -0.4 -3.901 90)
			(layer "B.Fab")
			(effects
				(font
					(size 0.7 0.7)
					(thickness 0.15)
				)
				(justify right top mirror)
			)
		)
		(pad "1" smd circle
			(at 0 0 90)
			(size 0.75 0.75)
			(layers "B.Cu" "B.Mask")
			(net 700 "Net-(J1A-MV_LSW_MON)")
			(pinfunction "1")
			(pintype "passive")
		)
	)
	(footprint "antmicro-footprints:R_0402_1005Metric"
		(layer "B.Cu")
		(at 203.4 104.8)
		(descr "Resistor SMD 0402")
		(tags "resistor SMD 0402")
		(property "Reference" "R282"
			(at 2.9 -0.35 0)
			(layer "B.SilkS")
			(effects
				(font
					(size 0.7 0.7)
					(thickness 0.15)
				)
				(justify right top mirror)
			)
		)
		(property "Value" "R_0R_0402"
			(at -1.011843 -1.772046 0)
			(layer "B.Fab")
			(effects
				(font
					(size 0.7 0.7)
					(thickness 0.15)
				)
				(justify right top mirror)
			)
		)
		(property "Datasheet" "https://industrial.panasonic.com/cdbs/www-data/pdf/RDA0000/AOA0000C301.pdf"
			(at 0 0 0)
			(layer "B.Fab")
			(hide yes)
			(effects
				(font
					(size 1.27 1.27)
					(thickness 0.15)
				)
				(justify mirror)
			)
		)
		(property "Description" "SMD Chip Resistor, Jumper, 0 ohm, 100 mW, 0402 [1005 Metric], Thick Film, General Purpose"
			(at 0 0 0)
			(layer "B.Fab")
			(hide yes)
			(effects
				(font
					(size 1.27 1.27)
					(thickness 0.15)
				)
				(justify mirror)
			)
		)
		(property "Manufacturer" "Panasonic"
			(at 0 0 180)
			(unlocked yes)
			(layer "B.Fab")
			(hide yes)
			(effects
				(font
					(size 1 1)
					(thickness 0.15)
				)
				(justify mirror)
			)
		)
		(property "MPN" "ERJ2GE0R00X"
			(at 0 0 180)
			(unlocked yes)
			(layer "B.Fab")
			(hide yes)
			(effects
				(font
					(size 1 1)
					(thickness 0.15)
				)
				(justify mirror)
			)
		)
		(property "Val" "0R"
			(at 0 0 180)
			(unlocked yes)
			(layer "B.Fab")
			(hide yes)
			(effects
				(font
					(size 1 1)
					(thickness 0.15)
				)
				(justify mirror)
			)
		)
		(property "License" "Apache-2.0"
			(at 0 0 180)
			(unlocked yes)
			(layer "B.Fab")
			(hide yes)
			(effects
				(font
					(size 1 1)
					(thickness 0.15)
				)
				(justify mirror)
			)
		)
		(property "Author" "Antmicro"
			(at 0 0 180)
			(unlocked yes)
			(layer "B.Fab")
			(hide yes)
			(effects
				(font
					(size 1 1)
					(thickness 0.15)
				)
				(justify mirror)
			)
		)
		(property "Tolerance" "~"
			(at 0 0 180)
			(unlocked yes)
			(layer "B.Fab")
			(hide yes)
			(effects
				(font
					(size 1 1)
					(thickness 0.15)
				)
				(justify mirror)
			)
		)
		(property "Current" "1A"
			(at 0 0 180)
			(unlocked yes)
			(layer "B.Fab")
			(hide yes)
			(effects
				(font
					(size 1 1)
					(thickness 0.15)
				)
				(justify mirror)
			)
		)
		(sheetname "/Recovery USB/")
		(sheetfile "recovery_usb.kicad_sch")
		(attr smd exclude_from_pos_files exclude_from_bom dnp)
		(fp_poly
			(pts
				(xy -0.925 0.47) (xy -0.925 -0.47) (xy 0.925 -0.47) (xy 0.925 0.47)
			)
			(stroke
				(width 0.05)
				(type default)
			)
			(fill no)
			(layer "B.CrtYd")
		)
		(fp_poly
			(pts
				(xy -0.5 0.25) (xy -0.5 -0.25) (xy 0.5 -0.25) (xy 0.5 0.25)
			)
			(stroke
				(width 0.15)
				(type solid)
			)
			(fill no)
			(layer "B.Fab")
		)
		(fp_text user "Author: Antmicro"
			(at -0.95 -4.169 0)
			(layer "B.Fab")
			(effects
				(font
					(size 0.7 0.7)
					(thickness 0.15)
				)
				(justify right top mirror)
			)
		)
		(fp_text user "${REFERENCE}"
			(at -0.95 -3.168 0)
			(layer "B.Fab")
			(effects
				(font
					(size 0.7 0.7)
					(thickness 0.15)
				)
				(justify right top mirror)
			)
		)
		(fp_text user "License: Apache-2.0"
			(at -0.949999 -5.169 0)
			(layer "B.Fab")
			(effects
				(font
					(size 0.7 0.7)
					(thickness 0.15)
				)
				(justify right top mirror)
			)
		)
		(pad "1" smd roundrect
			(at -0.48 0)
			(size 0.59 0.64)
			(layers "B.Cu" "B.Mask" "B.Paste")
			(roundrect_rratio 0.25)
			(net 853 "/I2C_{SYS}.SCL")
			(pintype "passive")
		)
		(pad "2" smd roundrect
			(at 0.48 0)
			(size 0.59 0.64)
			(layers "B.Cu" "B.Mask" "B.Paste")
			(roundrect_rratio 0.25)
			(net 1025 "/Recovery USB/USBC2_I2C_SCL")
			(pintype "passive")
		)
	)
	(footprint "antmicro-footprints:R_0402_1005Metric"
		(layer "B.Cu")
		(at 235.2 63.8)
		(descr "Resistor SMD 0402")
		(tags "resistor SMD 0402")
		(property "Reference" "R407"
			(at 1.3 -0.5 0)
			(layer "B.SilkS")
			(effects
				(font
					(size 0.7 0.7)
					(thickness 0.15)
				)
				(justify right top mirror)
			)
		)
		(property "Value" "R_470R_0402"
			(at -1.011843 -1.772046 0)
			(layer "B.Fab")
			(effects
				(font
					(size 0.7 0.7)
					(thickness 0.15)
				)
				(justify right top mirror)
			)
		)
		(property "Datasheet" "https://www.bourns.com/docs/product-datasheets/cr.pdf"
			(at 0 0 0)
			(layer "B.Fab")
			(hide yes)
			(effects
				(font
					(size 1.27 1.27)
					(thickness 0.15)
				)
				(justify mirror)
			)
		)
		(property "Description" "SMD Chip Resistor, 470 ohm, ± 1%, 62.5 mW, 0402 [1005 Metric], Thick Film, General Purpose"
			(at 0 0 0)
			(layer "B.Fab")
			(hide yes)
			(effects
				(font
					(size 1.27 1.27)
					(thickness 0.15)
				)
				(justify mirror)
			)
		)
		(property "Manufacturer" "Bourns"
			(at 0 0 180)
			(unlocked yes)
			(layer "B.Fab")
			(hide yes)
			(effects
				(font
					(size 1 1)
					(thickness 0.15)
				)
				(justify mirror)
			)
		)
		(property "MPN" "CR0402-FX-4700GLF"
			(at 0 0 180)
			(unlocked yes)
			(layer "B.Fab")
			(hide yes)
			(effects
				(font
					(size 1 1)
					(thickness 0.15)
				)
				(justify mirror)
			)
		)
		(property "Val" "470R"
			(at 0 0 180)
			(unlocked yes)
			(layer "B.Fab")
			(hide yes)
			(effects
				(font
					(size 1 1)
					(thickness 0.15)
				)
				(justify mirror)
			)
		)
		(property "License" "Apache-2.0"
			(at 0 0 180)
			(unlocked yes)
			(layer "B.Fab")
			(hide yes)
			(effects
				(font
					(size 1 1)
					(thickness 0.15)
				)
				(justify mirror)
			)
		)
		(property "Author" "Antmicro"
			(at 0 0 180)
			(unlocked yes)
			(layer "B.Fab")
			(hide yes)
			(effects
				(font
					(size 1 1)
					(thickness 0.15)
				)
				(justify mirror)
			)
		)
		(property "Tolerance" "1%"
			(at 0 0 180)
			(unlocked yes)
			(layer "B.Fab")
			(hide yes)
			(effects
				(font
					(size 1 1)
					(thickness 0.15)
				)
				(justify mirror)
			)
		)
		(sheetname "/SoM_Power/")
		(sheetfile "som_power.kicad_sch")
		(attr smd)
		(fp_poly
			(pts
				(xy -0.925 0.47) (xy 0.925 0.47) (xy 0.925 -0.47) (xy -0.925 -0.47)
			)
			(stroke
				(width 0.05)
				(type default)
			)
			(fill no)
			(layer "B.CrtYd")
		)
		(fp_poly
			(pts
				(xy -0.5 0.25) (xy 0.5 0.25) (xy 0.5 -0.25) (xy -0.5 -0.25)
			)
			(stroke
				(width 0.15)
				(type solid)
			)
			(fill no)
			(layer "B.Fab")
		)
		(fp_text user "Author: Antmicro"
			(at -0.95 -4.169 0)
			(layer "B.Fab")
			(effects
				(font
					(size 0.7 0.7)
					(thickness 0.15)
				)
				(justify right top mirror)
			)
		)
		(fp_text user "License: Apache-2.0"
			(at -0.949999 -5.169 0)
			(layer "B.Fab")
			(effects
				(font
					(size 0.7 0.7)
					(thickness 0.15)
				)
				(justify right top mirror)
			)
		)
		(fp_text user "${REFERENCE}"
			(at -0.95 -3.168 0)
			(layer "B.Fab")
			(effects
				(font
					(size 0.7 0.7)
					(thickness 0.15)
				)
				(justify right top mirror)
			)
		)
		(pad "1" smd roundrect
			(at -0.48 0)
			(size 0.59 0.64)
			(layers "B.Cu" "B.Mask" "B.Paste")
			(roundrect_rratio 0.25)
			(net 1394 "Net-(D65-A)")
			(pintype "passive")
		)
		(pad "2" smd roundrect
			(at 0.48 0)
			(size 0.59 0.64)
			(layers "B.Cu" "B.Mask" "B.Paste")
			(roundrect_rratio 0.25)
			(net 5 "+5V")
			(pintype "passive")
		)
	)
)
